(kicad_pcb
	(version 20241229)
	(generator "pcbnew")
	(generator_version "9.0")
	(general
		(thickness 1.62)
		(legacy_teardrops no)
	)
	(paper "A3")
	(title_block
		(title "COM Express 7 Baseboard")
		(date "2025-02-04")
		(rev "1.1.2")
		(company "Antmicro Ltd")
		(comment 1 "www.antmicro.com")
		(comment 9 "footprints 292-296 of 802")
	)
	(layers
		(0 "F.Cu" signal)
		(4 "In1.Cu" signal)
		(6 "In2.Cu" signal)
		(8 "In3.Cu" signal)
		(10 "In4.Cu" signal)
		(12 "In5.Cu" signal)
		(14 "In6.Cu" signal)
		(2 "B.Cu" signal)
		(9 "F.Adhes" user "F.Adhesive")
		(11 "B.Adhes" user "B.Adhesive")
		(13 "F.Paste" user)
		(15 "B.Paste" user)
		(5 "F.SilkS" user "F.Silkscreen")
		(7 "B.SilkS" user "B.Silkscreen")
		(1 "F.Mask" user)
		(3 "B.Mask" user)
		(17 "Dwgs.User" user "User.Drawings")
		(19 "Cmts.User" user "User.Comments")
		(21 "Eco1.User" user "User.Eco1")
		(23 "Eco2.User" user "User.Eco2")
		(25 "Edge.Cuts" user)
		(27 "Margin" user)
		(31 "F.CrtYd" user "F.Courtyard")
		(29 "B.CrtYd" user "B.Courtyard")
		(35 "F.Fab" user)
		(33 "B.Fab" user)
	)
	(footprint "antmicro-footprints:LED_0603_1608Metric_G"
		(layer "F.Cu")
		(at 197.70861 74.802163 90)
		(descr "LED SMD 0603 Green")
		(tags "LED SMD 0603 Green")
		(property "Reference" "D28"
			(at -1.1 -0.55 90)
			(layer "F.SilkS")
			(effects
				(font
					(size 0.7 0.7)
					(thickness 0.15)
				)
				(justify left bottom)
			)
		)
		(property "Value" "LED_G_0603_LTST-C190GKT"
			(at -0.001 1.599 90)
			(layer "F.Fab")
			(effects
				(font
					(size 0.7 0.7)
					(thickness 0.15)
				)
				(justify left bottom)
			)
		)
		(property "Datasheet" "https://media.digikey.com/pdf/Data%20Sheets/Lite-On%20PDFs/LTST-C190GKT.pdf"
			(at 0 0 90)
			(layer "F.Fab")
			(hide yes)
			(effects
				(font
					(size 1.27 1.27)
					(thickness 0.15)
				)
			)
		)
		(property "Author" "Antmicro"
			(at 272.510773 -122.906447 0)
			(layer "F.Fab")
			(hide yes)
			(effects
				(font
					(size 1 1)
					(thickness 0.15)
				)
			)
		)
		(property "Color" "Green"
			(at 272.510773 -122.906447 0)
			(layer "F.Fab")
			(hide yes)
			(effects
				(font
					(size 1 1)
					(thickness 0.15)
				)
			)
		)
		(property "License" "Apache-2.0"
			(at 272.510773 -122.906447 0)
			(layer "F.Fab")
			(hide yes)
			(effects
				(font
					(size 1 1)
					(thickness 0.15)
				)
			)
		)
		(property "MPN" "LTST-C190GKT"
			(at 272.510773 -122.906447 0)
			(layer "F.Fab")
			(hide yes)
			(effects
				(font
					(size 1 1)
					(thickness 0.15)
				)
			)
		)
		(property "Manufacturer" "Lite-On"
			(at 272.510773 -122.906447 0)
			(layer "F.Fab")
			(hide yes)
			(effects
				(font
					(size 1 1)
					(thickness 0.15)
				)
			)
		)
		(property "Public" "False"
			(at 272.510773 -122.906447 0)
			(layer "F.Fab")
			(hide yes)
			(effects
				(font
					(size 1 1)
					(thickness 0.15)
				)
			)
		)
		(sheetname "Power")
		(sheetfile "power.kicad_sch")
		(attr smd)
		(fp_line
			(start 0.22 -0.35)
			(end -0.22 -0.35)
			(stroke
				(width 0.15)
				(type solid)
			)
			(layer "F.SilkS")
		)
		(fp_line
			(start -1.18 -0.319)
			(end -1.18 0.321)
			(stroke
				(width 0.15)
				(type solid)
			)
			(layer "F.SilkS")
		)
		(fp_line
			(start 0.105328 0.001008)
			(end 0.24 0.001)
			(stroke
				(width 0.1)
				(type solid)
			)
			(layer "F.SilkS")
		)
		(fp_line
			(start -0.094672 0.001008)
			(end 0.105328 -0.198992)
			(stroke
				(width 0.1)
				(type solid)
			)
			(layer "F.SilkS")
		)
		(fp_line
			(start -0.094672 0.001008)
			(end -0.24 0.001008)
			(stroke
				(width 0.1)
				(type solid)
			)
			(layer "F.SilkS")
		)
		(fp_line
			(start 0.105328 0.201008)
			(end 0.105328 -0.198992)
			(stroke
				(width 0.1)
				(type solid)
			)
			(layer "F.SilkS")
		)
		(fp_line
			(start 0.105328 0.201008)
			(end -0.094672 0.001008)
			(stroke
				(width 0.1)
				(type solid)
			)
			(layer "F.SilkS")
		)
		(fp_line
			(start -0.094672 0.201008)
			(end -0.094672 -0.198992)
			(stroke
				(width 0.1)
				(type solid)
			)
			(layer "F.SilkS")
		)
		(fp_line
			(start 0.22 0.35)
			(end -0.22 0.35)
			(stroke
				(width 0.15)
				(type solid)
			)
			(layer "F.SilkS")
		)
		(fp_rect
			(start 1.25 0.65)
			(end -1.25 -0.65)
			(stroke
				(width 0.05)
				(type solid)
			)
			(fill no)
			(layer "F.CrtYd")
		)
		(fp_line
			(start 0.201 -0.202)
			(end -0.101 0)
			(stroke
				(width 0.15)
				(type solid)
			)
			(layer "F.Fab")
		)
		(fp_line
			(start -0.199 -0.202)
			(end -0.199 0.1)
			(stroke
				(width 0.15)
				(type solid)
			)
			(layer "F.Fab")
		)
		(fp_line
			(start 0.599 0)
			(end 0.201 0)
			(stroke
				(width 0.15)
				(type solid)
			)
			(layer "F.Fab")
		)
		(fp_line
			(start 0.201 0)
			(end 0.201 -0.202)
			(stroke
				(width 0.15)
				(type solid)
			)
			(layer "F.Fab")
		)
		(fp_line
			(start -0.101 0)
			(end 0.201 0.2)
			(stroke
				(width 0.15)
				(type solid)
			)
			(layer "F.Fab")
		)
		(fp_line
			(start -0.199 0)
			(end -0.597 0)
			(stroke
				(width 0.15)
				(type solid)
			)
			(layer "F.Fab")
		)
		(fp_line
			(start 0.201 0.2)
			(end 0.201 0)
			(stroke
				(width 0.15)
				(type solid)
			)
			(layer "F.Fab")
		)
		(fp_line
			(start -0.199 0.2)
			(end -0.199 0.1)
			(stroke
				(width 0.15)
				(type solid)
			)
			(layer "F.Fab")
		)
		(fp_rect
			(start 0.848 0.4)
			(end -0.85 -0.402)
			(stroke
				(width 0.15)
				(type solid)
			)
			(fill no)
			(layer "F.Fab")
		)
		(pad "1" smd roundrect
			(at -0.7 0 270)
			(size 0.8 1)
			(layers "F.Cu" "F.Mask" "F.Paste")
			(roundrect_rratio 0.2)
			(net 981 "Net-(D28-C)")
			(pinfunction "C")
			(pintype "passive")
			(teardrops
				(best_length_ratio 0.2)
				(max_length 1)
				(best_width_ratio 0.9)
				(max_width 2)
				(curved_edges yes)
				(filter_ratio 0.9)
				(enabled yes)
				(allow_two_segments yes)
				(prefer_zone_connections yes)
			)
		)
		(pad "2" smd roundrect
			(at 0.7 0 270)
			(size 0.8 1)
			(layers "F.Cu" "F.Mask" "F.Paste")
			(roundrect_rratio 0.2)
			(net 2 "+3V3")
			(pinfunction "A")
			(pintype "passive")
			(teardrops
				(best_length_ratio 0.2)
				(max_length 1)
				(best_width_ratio 0.9)
				(max_width 2)
				(curved_edges yes)
				(filter_ratio 0.9)
				(enabled yes)
				(allow_two_segments yes)
				(prefer_zone_connections yes)
			)
		)
	)
	(footprint "antmicro-footprints:R_0402_1005Metric"
		(layer "F.Cu")
		(at 308.7 105.81 180)
		(descr "Resistor SMD 0402")
		(tags "resistor SMD 0402")
		(property "Reference" "R99"
			(at -1.15 -1.3 0)
			(layer "F.SilkS")
			(effects
				(font
					(size 0.7 0.7)
					(thickness 0.15)
				)
				(justify right bottom)
			)
		)
		(property "Value" "R_68k_0402"
			(at -1.011843 1.772047 0)
			(layer "F.Fab")
			(effects
				(font
					(size 0.7 0.7)
					(thickness 0.15)
				)
				(justify right bottom)
			)
		)
		(property "Datasheet" "https://www.bourns.com/docs/product-datasheets/cr.pdf"
			(at 0 0 180)
			(layer "F.Fab")
			(hide yes)
			(effects
				(font
					(size 1.27 1.27)
					(thickness 0.15)
				)
			)
		)
		(property "Author" "Antmicro"
			(at 617.4 211.62 0)
			(layer "F.Fab")
			(hide yes)
			(effects
				(font
					(size 1 1)
					(thickness 0.15)
				)
			)
		)
		(property "License" "Apache-2.0"
			(at 617.4 211.62 0)
			(layer "F.Fab")
			(hide yes)
			(effects
				(font
					(size 1 1)
					(thickness 0.15)
				)
			)
		)
		(property "MPN" "CR0402-FX-6802GLF"
			(at 617.4 211.62 0)
			(layer "F.Fab")
			(hide yes)
			(effects
				(font
					(size 1 1)
					(thickness 0.15)
				)
			)
		)
		(property "Manufacturer" "Bourns"
			(at 617.4 211.62 0)
			(layer "F.Fab")
			(hide yes)
			(effects
				(font
					(size 1 1)
					(thickness 0.15)
				)
			)
		)
		(property "Public" "False"
			(at 617.4 211.62 0)
			(layer "F.Fab")
			(hide yes)
			(effects
				(font
					(size 1 1)
					(thickness 0.15)
				)
			)
		)
		(property "Tolerance" "1%"
			(at 617.4 211.62 0)
			(layer "F.Fab")
			(hide yes)
			(effects
				(font
					(size 1 1)
					(thickness 0.15)
				)
			)
		)
		(property "Val" "68k"
			(at 617.4 211.62 0)
			(layer "F.Fab")
			(hide yes)
			(effects
				(font
					(size 1 1)
					(thickness 0.15)
				)
			)
		)
		(sheetname "Power")
		(sheetfile "power.kicad_sch")
		(attr smd)
		(fp_rect
			(start -0.925 -0.47)
			(end 0.925 0.47)
			(stroke
				(width 0.05)
				(type default)
			)
			(fill no)
			(layer "F.CrtYd")
		)
		(fp_rect
			(start -0.5 -0.25)
			(end 0.5 0.25)
			(stroke
				(width 0.15)
				(type solid)
			)
			(fill no)
			(layer "F.Fab")
		)
		(pad "1" smd roundrect
			(at -0.48 0 180)
			(size 0.59 0.64)
			(layers "F.Cu" "F.Mask" "F.Paste")
			(roundrect_rratio 0.25)
			(net 581 "Net-(U19-FB)")
			(pintype "passive")
			(teardrops
				(best_length_ratio 0.2)
				(max_length 1)
				(best_width_ratio 0.9)
				(max_width 2)
				(curved_edges yes)
				(filter_ratio 0.9)
				(enabled yes)
				(allow_two_segments yes)
				(prefer_zone_connections yes)
			)
		)
		(pad "2" smd roundrect
			(at 0.48 0 180)
			(size 0.59 0.64)
			(layers "F.Cu" "F.Mask" "F.Paste")
			(roundrect_rratio 0.25)
			(net 71 "Net-(U49-IN+)")
			(pintype "passive")
			(teardrops
				(best_length_ratio 0.2)
				(max_length 1)
				(best_width_ratio 0.9)
				(max_width 2)
				(curved_edges yes)
				(filter_ratio 0.9)
				(enabled yes)
				(allow_two_segments yes)
				(prefer_zone_connections yes)
			)
		)
	)
	(footprint "antmicro-footprints:C_0603_1608Metric"
		(layer "F.Cu")
		(at 177.52 93.22)
		(descr "Capacitor SMD 0603")
		(tags "capacitor 0603")
		(property "Reference" "C71"
			(at -3.27 0.49 0)
			(layer "F.SilkS")
			(effects
				(font
					(size 0.7 0.7)
					(thickness 0.15)
				)
				(justify left bottom)
			)
		)
		(property "Value" "C_22u_16V_0603"
			(at -1.42757 1.770288 0)
			(layer "F.Fab")
			(effects
				(font
					(size 0.7 0.7)
					(thickness 0.15)
				)
				(justify left bottom)
			)
		)
		(property "Datasheet" "https://product.samsungsem.com/mlcc/CL10A226MO7JZN.do"
			(at 0 0 0)
			(layer "F.Fab")
			(hide yes)
			(effects
				(font
					(size 1.27 1.27)
					(thickness 0.15)
				)
			)
		)
		(property "Author" "Antmicro"
			(at 0 0 0)
			(layer "F.Fab")
			(hide yes)
			(effects
				(font
					(size 1 1)
					(thickness 0.15)
				)
			)
		)
		(property "Dielectric" ""
			(at 0 0 0)
			(layer "F.Fab")
			(hide yes)
			(effects
				(font
					(size 1 1)
					(thickness 0.15)
				)
			)
		)
		(property "License" "Apache-2.0"
			(at 0 0 0)
			(layer "F.Fab")
			(hide yes)
			(effects
				(font
					(size 1 1)
					(thickness 0.15)
				)
			)
		)
		(property "MPN" "CL10A226MO7JZNC"
			(at 0 0 0)
			(layer "F.Fab")
			(hide yes)
			(effects
				(font
					(size 1 1)
					(thickness 0.15)
				)
			)
		)
		(property "Manufacturer" "Samsung Electro-Mechanics"
			(at 0 0 0)
			(layer "F.Fab")
			(hide yes)
			(effects
				(font
					(size 1 1)
					(thickness 0.15)
				)
			)
		)
		(property "Public" "False"
			(at 0 0 0)
			(layer "F.Fab")
			(hide yes)
			(effects
				(font
					(size 1 1)
					(thickness 0.15)
				)
			)
		)
		(property "Val" "22u"
			(at 0 0 0)
			(layer "F.Fab")
			(hide yes)
			(effects
				(font
					(size 1 1)
					(thickness 0.15)
				)
			)
		)
		(property "Voltage" "16V"
			(at 0 0 0)
			(layer "F.Fab")
			(hide yes)
			(effects
				(font
					(size 1 1)
					(thickness 0.15)
				)
			)
		)
		(sheetname "M.2 key M #1")
		(sheetfile "m2keym_low.kicad_sch")
		(attr smd)
		(fp_line
			(start -0.15 -0.4)
			(end 0.15 -0.4)
			(stroke
				(width 0.15)
				(type solid)
			)
			(layer "F.SilkS")
		)
		(fp_line
			(start -0.15 0.4)
			(end 0.15 0.4)
			(stroke
				(width 0.15)
				(type solid)
			)
			(layer "F.SilkS")
		)
		(fp_rect
			(start -1.25 -0.65)
			(end 1.25 0.65)
			(stroke
				(width 0.05)
				(type solid)
			)
			(fill no)
			(layer "F.CrtYd")
		)
		(fp_rect
			(start -0.8 -0.4)
			(end 0.8 0.4)
			(stroke
				(width 0.15)
				(type solid)
			)
			(fill no)
			(layer "F.Fab")
		)
		(pad "1" smd roundrect
			(at -0.7 0)
			(size 0.8 1)
			(layers "F.Cu" "F.Mask" "F.Paste")
			(roundrect_rratio 0.2)
			(net 1 "GND")
			(pintype "passive")
			(teardrops
				(best_length_ratio 0.2)
				(max_length 1)
				(best_width_ratio 0.9)
				(max_width 2)
				(curved_edges yes)
				(filter_ratio 0.9)
				(enabled yes)
				(allow_two_segments yes)
				(prefer_zone_connections yes)
			)
		)
		(pad "2" smd roundrect
			(at 0.7 0)
			(size 0.8 1)
			(layers "F.Cu" "F.Mask" "F.Paste")
			(roundrect_rratio 0.2)
			(net 969 "/M.2 key M #1/M2_3V3")
			(pintype "passive")
			(teardrops
				(best_length_ratio 0.2)
				(max_length 1)
				(best_width_ratio 0.9)
				(max_width 2)
				(curved_edges yes)
				(filter_ratio 0.9)
				(enabled yes)
				(allow_two_segments yes)
				(prefer_zone_connections yes)
			)
		)
	)
	(footprint "antmicro-footprints:TP_SMD_0.75mm"
		(layer "F.Cu")
		(at 195.315076 131.515076 45)
		(property "Reference" "TP56"
			(at 0.4 0.4 45)
			(layer "F.SilkS")
			(effects
				(font
					(size 0.7 0.7)
					(thickness 0.15)
				)
				(justify left bottom)
			)
		)
		(property "Value" "TP_0.75mm_SMD"
			(at 0 1.2 45)
			(layer "F.Fab")
			(effects
				(font
					(size 0.7 0.7)
					(thickness 0.15)
				)
				(justify left bottom)
			)
		)
		(property "Author" "Antmicro"
			(at 369.6 -267.02 45)
			(layer "F.Fab")
			(hide yes)
			(effects
				(font
					(size 1 1)
					(thickness 0.15)
				)
			)
		)
		(property "License" "Apache-2.0"
			(at 369.6 -267.02 45)
			(layer "F.Fab")
			(hide yes)
			(effects
				(font
					(size 1 1)
					(thickness 0.15)
				)
			)
		)
		(property "MPN" ""
			(at 369.6 -267.02 45)
			(layer "F.Fab")
			(hide yes)
			(effects
				(font
					(size 1 1)
					(thickness 0.15)
				)
			)
		)
		(property "Manufacturer" ""
			(at 369.6 -267.02 45)
			(layer "F.Fab")
			(hide yes)
			(effects
				(font
					(size 1 1)
					(thickness 0.15)
				)
			)
		)
		(property "Public" "False"
			(at 369.6 -267.02 45)
			(layer "F.Fab")
			(hide yes)
			(effects
				(font
					(size 1 1)
					(thickness 0.15)
				)
			)
		)
		(sheetname "PCIe redriver")
		(sheetfile "pcie_redriver.kicad_sch")
		(attr exclude_from_pos_files exclude_from_bom)
		(fp_circle
			(center 0 0)
			(end 0.475 0)
			(stroke
				(width 0.05)
				(type default)
			)
			(fill no)
			(layer "F.CrtYd")
		)
		(pad "1" smd circle
			(at 0 0 45)
			(size 0.75 0.75)
			(layers "F.Cu" "F.Mask")
			(net 719 "Net-(U40-~{I2C_{RESET}})")
			(pinfunction "1")
			(pintype "passive")
			(teardrops
				(best_length_ratio 0.4)
				(max_length 1)
				(best_width_ratio 0.9)
				(max_width 2)
				(curved_edges yes)
				(filter_ratio 0.9)
				(enabled yes)
				(allow_two_segments yes)
				(prefer_zone_connections yes)
			)
		)
	)
	(footprint "antmicro-footprints:TSOT23-6"
		(layer "F.Cu")
		(at 116.9 86.86)
		(property "Reference" "U3"
			(at -0.75 -1.75 0)
			(layer "F.SilkS")
			(effects
				(font
					(size 0.7 0.7)
					(thickness 0.15)
				)
				(justify left bottom)
			)
		)
		(property "Value" "AP22615A_TSOT26"
			(at 0 2.6 0)
			(layer "F.Fab")
			(effects
				(font
					(size 0.7 0.7)
					(thickness 0.15)
				)
				(justify left bottom)
			)
		)
		(property "Datasheet" "https://www.mouser.com/datasheet/2/115/DIOD_S_A0008958405_1-2543193.pdf"
			(at 0 0 0)
			(layer "F.Fab")
			(hide yes)
			(effects
				(font
					(size 1.27 1.27)
					(thickness 0.15)
				)
			)
		)
		(property "Author" "Antmicro"
			(at 0 0 0)
			(layer "F.Fab")
			(hide yes)
			(effects
				(font
					(size 1 1)
					(thickness 0.15)
				)
			)
		)
		(property "License" "Apache-2.0"
			(at 0 0 0)
			(layer "F.Fab")
			(hide yes)
			(effects
				(font
					(size 1 1)
					(thickness 0.15)
				)
			)
		)
		(property "MPN" "AP22615AWU-7"
			(at 0 0 0)
			(layer "F.Fab")
			(hide yes)
			(effects
				(font
					(size 1 1)
					(thickness 0.15)
				)
			)
		)
		(property "Manufacturer" "Diodes Incorporated"
			(at 0 0 0)
			(layer "F.Fab")
			(hide yes)
			(effects
				(font
					(size 1 1)
					(thickness 0.15)
				)
			)
		)
		(sheetname "2xUSB3.0+RJ45")
		(sheetfile "usb3+rj45.kicad_sch")
		(attr smd)
		(fp_line
			(start -1 -1.5)
			(end -1 -1.375)
			(stroke
				(width 0.15)
				(type solid)
			)
			(layer "F.SilkS")
		)
		(fp_line
			(start -1 1.55)
			(end -1 1.4)
			(stroke
				(width 0.15)
				(type solid)
			)
			(layer "F.SilkS")
		)
		(fp_line
			(start 1 -1.497)
			(end -1 -1.5)
			(stroke
				(width 0.15)
				(type solid)
			)
			(layer "F.SilkS")
		)
		(fp_line
			(start 1 -1.497)
			(end 1 -1.375)
			(stroke
				(width 0.15)
				(type solid)
			)
			(layer "F.SilkS")
		)
		(fp_line
			(start 1 1.55)
			(end -1 1.55)
			(stroke
				(width 0.15)
				(type solid)
			)
			(layer "F.SilkS")
		)
		(fp_line
			(start 1 1.55)
			(end 1 1.4)
			(stroke
				(width 0.15)
				(type solid)
			)
			(layer "F.SilkS")
		)
		(fp_circle
			(center -1.44 -1.5)
			(end -1.39 -1.5)
			(stroke
				(width 0.15)
				(type solid)
			)
			(fill yes)
			(layer "F.SilkS")
		)
		(fp_rect
			(start 1.93 -1.7)
			(end -1.93 1.7)
			(stroke
				(width 0.05)
				(type solid)
			)
			(fill no)
			(layer "F.CrtYd")
		)
		(fp_line
			(start -0.45 -1.521)
			(end -0.876 -1.096)
			(stroke
				(width 0.15)
				(type solid)
			)
			(layer "F.Fab")
		)
		(fp_rect
			(start 0.875 1.528)
			(end -0.875 -1.525)
			(stroke
				(width 0.15)
				(type solid)
			)
			(fill no)
			(layer "F.Fab")
		)
		(pad "1" smd rect
			(at -1.301 -0.947 270)
			(size 0.7 1.2)
			(layers "F.Cu" "F.Mask" "F.Paste")
			(net 42 "/2xUSB3.0+RJ45/P1_VBUS")
			(pinfunction "OUT")
			(pintype "power_out")
			(teardrops
				(best_length_ratio 0.2)
				(max_length 1)
				(best_width_ratio 0.9)
				(max_width 2)
				(curved_edges yes)
				(filter_ratio 0.9)
				(enabled yes)
				(allow_two_segments yes)
				(prefer_zone_connections yes)
			)
		)
		(pad "2" smd rect
			(at -1.301 0.004 270)
			(size 0.7 1.2)
			(layers "F.Cu" "F.Mask" "F.Paste")
			(net 1 "GND")
			(pinfunction "GND")
			(pintype "power_in")
			(teardrops
				(best_length_ratio 0.2)
				(max_length 1)
				(best_width_ratio 0.9)
				(max_width 2)
				(curved_edges yes)
				(filter_ratio 0.9)
				(enabled yes)
				(allow_two_segments yes)
				(prefer_zone_connections yes)
			)
		)
		(pad "3" smd rect
			(at -1.301 0.954 270)
			(size 0.7 1.2)
			(layers "F.Cu" "F.Mask" "F.Paste")
			(net 553 "/2xUSB3.0+RJ45/FLG_1B")
			(pinfunction "FLG")
			(pintype "output")
			(teardrops
				(best_length_ratio 0.2)
				(max_length 1)
				(best_width_ratio 0.9)
				(max_width 2)
				(curved_edges yes)
				(filter_ratio 0.9)
				(enabled yes)
				(allow_two_segments yes)
				(prefer_zone_connections yes)
			)
		)
		(pad "4" smd rect
			(at 1.299 0.954 270)
			(size 0.7 1.2)
			(layers "F.Cu" "F.Mask" "F.Paste")
			(net 555 "/2xUSB3.0+RJ45/EN_1B")
			(pinfunction "EN")
			(pintype "input")
			(teardrops
				(best_length_ratio 0.2)
				(max_length 1)
				(best_width_ratio 0.9)
				(max_width 2)
				(curved_edges yes)
				(filter_ratio 0.9)
				(enabled yes)
				(allow_two_segments yes)
				(prefer_zone_connections yes)
			)
		)
		(pad "5" smd rect
			(at 1.299 0.004 270)
			(size 0.7 1.2)
			(layers "F.Cu" "F.Mask" "F.Paste")
			(net 547 "/2xUSB3.0+RJ45/P1_ISET")
			(pinfunction "ISET")
			(pintype "passive")
			(teardrops
				(best_length_ratio 0.2)
				(max_length 1)
				(best_width_ratio 0.9)
				(max_width 2)
				(curved_edges yes)
				(filter_ratio 0.9)
				(enabled yes)
				(allow_two_segments yes)
				(prefer_zone_connections yes)
			)
		)
		(pad "6" smd rect
			(at 1.299 -0.947 270)
			(size 0.7 1.2)
			(layers "F.Cu" "F.Mask" "F.Paste")
			(net 52 "+5V")
			(pinfunction "IN")
			(pintype "power_in")
			(teardrops
				(best_length_ratio 0.2)
				(max_length 1)
				(best_width_ratio 0.9)
				(max_width 2)
				(curved_edges yes)
				(filter_ratio 0.9)
				(enabled yes)
				(allow_two_segments yes)
				(prefer_zone_connections yes)
			)
		)
	)
)
